# S9S_MB_2U (Grand Teton) — schematic netlist excerpt (pin names and nets, part order shuffled) for the footprints in the layout excerpt that follows; sources: Cadence DE-HDL packaged netlist, KiCad conversion of 03242023_DA0F0TMBIJ0_F0T_Motherboard_J_brd_V01_OCP.brd

PU49  RAA2213404GNPHB0  RAA2213404GNP#HB0 IC  pkg PQFN17_TH_5X4  page 294
  TMON  = PVCCFA_EHV_CPU1_BTSEN
  \fault#\  = PVCCFA_EHV_CPU1_FAULT
  LGCTRL  = PVCCFA_EHV_CPU1_NC1
  VCC  = PVCCFA_EHV_CPU1_VDD1
  GL1  = PVCCFA_EHV_CPU1_LSET1
  GND1  = GND
  SW  = SW_PVCCFA_EHV_CPU1_SW1
  VIN  = SW_P12V_PVCCINFAON_CPU1_FLT
  PHASE  = SW_PVCCFA_EHV_CPU1_BOOTR1
  BOOT  = SW_PVCCFA_EHV_CPU1_BOOT1
  PWM  = PVCCFA_EHV_CPU1_BPWM1
  NC1  = PVCCFA_EHV_CPU1_NC2
  GND2  = GND
  REFIN  = PVCCINFAON_CPU1_VREF
  IMON  = PVCCFA_EHV_CPU1_BCSP1
  GND3  = GND
  GL2  = NC

(kicad_pcb
	(version 20260206)
	(generator "pcbnew")
	(generator_version "10.0")
	(general
		(thickness 1.6)
		(legacy_teardrops no)
	)
	(paper "A4")
	(title_block
		(title "03242023_DA0F0TMBIJ0_F0T_Motherboard_J_brd_V01_OCP.brd")
		(comment 1 "Grand Teton / footprints 3157-3157 of 6105")
	)
	(layers
		(0 "F.Cu" signal "TOP")
		(4 "In1.Cu" signal "GND")
		(6 "In2.Cu" signal "IN1")
		(8 "In3.Cu" signal "GND1")
		(10 "In4.Cu" signal "IN2")
		(12 "In5.Cu" signal "GND2")
		(14 "In6.Cu" signal "IN3")
		(16 "In7.Cu" signal "GND3")
		(18 "In8.Cu" signal "VCC")
		(20 "In9.Cu" signal "VCC1")
		(22 "In10.Cu" signal "GND4")
		(24 "In11.Cu" signal "IN4")
		(26 "In12.Cu" signal "GND5")
		(28 "In13.Cu" signal "IN5")
		(30 "In14.Cu" signal "GND6")
		(32 "In15.Cu" signal "IN6")
		(34 "In16.Cu" signal "GND7")
		(2 "B.Cu" signal "BOTTOM")
		(9 "F.Adhes" user "F.Adhesive")
		(11 "B.Adhes" user "B.Adhesive")
		(13 "F.Paste" user "Package Geometry/Pastemask Top")
		(15 "B.Paste" user "Package Geometry/Pastemask Bottom")
		(5 "F.SilkS" user "Ref Des/Silkscreen Top")
		(7 "B.SilkS" user "Ref Des/Silkscreen Bottom")
		(1 "F.Mask" user "Board Geometry/Soldermask Top")
		(3 "B.Mask" user "Board Geometry/Soldermask Bottom")
		(17 "Dwgs.User" user "User.Drawings")
		(19 "Cmts.User" user "User.Comments")
		(21 "Eco1.User" user "User.Eco1")
		(23 "Eco2.User" user "User.Eco2")
		(25 "Edge.Cuts" user "Board Geometry/Outline")
		(27 "Margin" user)
		(31 "F.CrtYd" user "Package Geometry/Place Bound Top")
		(29 "B.CrtYd" user "Package Geometry/Place Bound Bottom")
		(35 "F.Fab" user "Ref Des/Assembly Top")
		(33 "B.Fab" user "Ref Des/Assembly Bottom")
	)
	(footprint ""
		(layer "F.Cu")
		(at 53.190902 -174.230792 90)
		(property "Reference" "PU49"
			(at 1.292606 -8.370062 0)
			(unlocked yes)
			(layer "F.SilkS")
			(effects
				(font
					(size 0.7874 0.5842)
					(thickness 0.1524)
				)
				(justify left)
			)
		)
		(property "Value" ""
			(at 0 0 90)
			(layer "F.Fab")
			(effects
				(font
					(size 1.27 1.27)
				)
			)
		)
		(duplicate_pad_numbers_are_jumpers no)
		(fp_line
			(start 2.050034 -2.549906)
			(end 1.916684 -2.549906)
			(stroke
				(width 0.1524)
				(type default)
			)
			(layer "F.SilkS")
		)
		(fp_line
			(start -1.61671 -2.549906)
			(end -2.050034 -2.549906)
			(stroke
				(width 0.1524)
				(type default)
			)
			(layer "F.SilkS")
		)
		(fp_line
			(start -2.050034 -2.549906)
			(end -2.050034 -2.126742)
			(stroke
				(width 0.1524)
				(type default)
			)
			(layer "F.SilkS")
		)
		(fp_line
			(start 2.050034 -1.981708)
			(end 2.050034 -2.549906)
			(stroke
				(width 0.1524)
				(type default)
			)
			(layer "F.SilkS")
		)
		(fp_line
			(start 2.050034 0.08636)
			(end 2.050034 -0.178308)
			(stroke
				(width 0.1524)
				(type default)
			)
			(layer "F.SilkS")
		)
		(fp_line
			(start -2.050034 0.406654)
			(end -2.050034 0.786384)
			(stroke
				(width 0.1524)
				(type default)
			)
			(layer "F.SilkS")
		)
		(fp_line
			(start -2.050034 1.88976)
			(end -2.050034 2.549906)
			(stroke
				(width 0.1524)
				(type default)
			)
			(layer "F.SilkS")
		)
		(fp_line
			(start 2.050034 2.549906)
			(end 2.050034 1.88976)
			(stroke
				(width 0.1524)
				(type default)
			)
			(layer "F.SilkS")
		)
		(fp_line
			(start 1.27 2.549906)
			(end 2.050034 2.549906)
			(stroke
				(width 0.1524)
				(type default)
			)
			(layer "F.SilkS")
		)
		(fp_line
			(start -2.050034 2.549906)
			(end -1.27 2.549906)
			(stroke
				(width 0.1524)
				(type default)
			)
			(layer "F.SilkS")
		)
		(fp_poly
			(pts
				(xy -2.33553 -1.898142) (xy -2.711704 -1.710182) (xy -2.711704 -2.086102)
			)
			(stroke
				(width 0)
				(type default)
			)
			(fill yes)
			(layer "F.SilkS")
		)
		(fp_line
			(start 2.050034 -2.549906)
			(end -2.050034 -2.549906)
			(stroke
				(width 0.1)
				(type default)
			)
			(layer "F.Fab")
		)
		(fp_line
			(start -2.050034 -2.549906)
			(end -2.050034 2.549906)
			(stroke
				(width 0.1)
				(type default)
			)
			(layer "F.Fab")
		)
		(fp_line
			(start 2.050034 2.549906)
			(end 2.050034 -2.549906)
			(stroke
				(width 0.1)
				(type default)
			)
			(layer "F.Fab")
		)
		(fp_line
			(start -2.050034 2.549906)
			(end 2.050034 2.549906)
			(stroke
				(width 0.1)
				(type default)
			)
			(layer "F.Fab")
		)
		(fp_poly
			(pts
				(xy -3.43789 -2.368042) (xy -3.43789 -1.352042) (xy -2.42189 -1.860042)
			)
			(stroke
				(width 0)
				(type default)
			)
			(fill yes)
			(layer "F.Fab")
		)
		(pad "1" smd rect
			(at -1.925066 -1.860042)
			(size 0.254 0.5588)
			(layers "F.Cu" "F.Mask" "F.Paste")
			(net "PVCCFA_EHV_CPU1_BTSEN")
		)
		(pad "2" smd rect
			(at -1.925066 -1.359916)
			(size 0.254 0.5588)
			(layers "F.Cu" "F.Mask" "F.Paste")
			(net "PVCCFA_EHV_CPU1_FAULT")
		)
		(pad "3" smd rect
			(at -1.925066 -0.860044)
			(size 0.254 0.5588)
			(layers "F.Cu" "F.Mask" "F.Paste")
			(net "PVCCFA_EHV_CPU1_NC1")
		)
		(pad "4" smd rect
			(at -1.925066 -0.359918)
			(size 0.254 0.5588)
			(layers "F.Cu" "F.Mask" "F.Paste")
			(net "PVCCFA_EHV_CPU1_VDD1")
		)
		(pad "5" smd rect
			(at -1.925066 0.139954)
			(size 0.254 0.5588)
			(layers "F.Cu" "F.Mask" "F.Paste")
			(net "PVCCFA_EHV_CPU1_LSET1")
		)
		(pad "6_7-13_15-29" smd circle
			(at 0 0.98806 180)
			(size 0 0)
			(layers "F.Cu" "F.Mask" "F.Paste")
			(net "GND")
		)
		(pad "8_12" smd rect
			(at 0 2.400046)
			(size 0.6096 2.2606)
			(layers "F.Cu" "F.Mask" "F.Paste")
			(net "SW_PVCCFA_EHV_CPU1_SW1")
		)
		(pad "16_18-28" smd rect
			(at 1.480566 -1.080008 90)
			(size 1.4478 1.524)
			(layers "F.Cu" "F.Mask" "F.Paste")
			(net "SW_P12V_PVCCINFAON_CPU1_FLT")
		)
		(pad "19" smd rect
			(at 1.649984 -2.424938 90)
			(size 0.254 0.5588)
			(layers "F.Cu" "F.Mask" "F.Paste")
			(net "SW_PVCCFA_EHV_CPU1_BOOTR1")
		)
		(pad "20" smd rect
			(at 1.150112 -2.424938 90)
			(size 0.254 0.5588)
			(layers "F.Cu" "F.Mask" "F.Paste")
			(net "SW_PVCCFA_EHV_CPU1_BOOT1")
		)
		(pad "21" smd rect
			(at 0.649986 -2.424938 90)
			(size 0.254 0.5588)
			(layers "F.Cu" "F.Mask" "F.Paste")
			(net "PVCCFA_EHV_CPU1_BPWM1")
		)
		(pad "22" smd rect
			(at 0.150114 -2.424938 90)
			(size 0.254 0.5588)
			(layers "F.Cu" "F.Mask" "F.Paste")
			(net "PVCCFA_EHV_CPU1_NC2")
		)
		(pad "23" smd rect
			(at -0.350012 -2.424938 90)
			(size 0.254 0.5588)
			(layers "F.Cu" "F.Mask" "F.Paste")
			(net "GND")
		)
		(pad "24" smd rect
			(at -0.849884 -2.424938 90)
			(size 0.254 0.5588)
			(layers "F.Cu" "F.Mask" "F.Paste")
			(net "PVCCINFAON_CPU1_VREF")
		)
		(pad "25" smd rect
			(at -1.35001 -2.424938 90)
			(size 0.254 0.5588)
			(layers "F.Cu" "F.Mask" "F.Paste")
			(net "PVCCFA_EHV_CPU1_BCSP1")
		)
		(pad "26" smd circle
			(at -0.490728 -1.009396 180)
			(size 0 0)
			(layers "F.Cu" "F.Mask" "F.Paste")
			(net "GND")
		)
		(pad "27" smd rect
			(at -1.124966 0.425958)
			(size 0.2032 0.3556)
			(layers "F.Cu" "F.Mask" "F.Paste")
			(net "Net_8493")
		)
		(zone
			(layer "F.Cu")
			(hatch none 0.5)
			(connect_pads
				(clearance 0)
			)
			(min_thickness 0.25)
			(keepout
				(tracks not_allowed)
				(vias allowed)
				(pads allowed)
				(copperpour not_allowed)
				(footprints allowed)
			)
			(placement
				(enabled no)
				(sheetname "")
			)
			(fill
				(thermal_gap 0.5)
				(thermal_bridge_width 0.5)
				(island_removal_mode 0)
			)
			(polygon
				(pts
					(xy 54.991762 -172.43552) (xy 54.991762 -175.979328) (xy 55.235348 -176.222914) (xy 55.235348 -172.191934)
				)
			)
		)
		(zone
			(layer "F.Cu")
			(hatch none 0.5)
			(connect_pads
				(clearance 0)
			)
			(min_thickness 0.25)
			(keepout
				(tracks not_allowed)
				(vias allowed)
				(pads allowed)
				(copperpour not_allowed)
				(footprints allowed)
			)
			(placement
				(enabled no)
				(sheetname "")
			)
			(fill
				(thermal_gap 0.5)
				(thermal_bridge_width 0.5)
				(island_removal_mode 0)
			)
			(polygon
				(pts
					(xy 53.3781 -173.734984) (xy 54.066186 -173.734984) (xy 54.066186 -172.180758) (xy 53.622702 -172.180758)
					(xy 53.622702 -172.877226) (xy 53.76926 -172.877226) (xy 53.76926 -173.334426) (xy 53.46446 -173.334426)
					(xy 53.46446 -172.877226) (xy 53.597302 -172.877226) (xy 53.597302 -172.180758) (xy 53.508656 -172.180758)
					(xy 53.508656 -172.635926) (xy 51.590702 -172.635926) (xy 51.590702 -172.812456) (xy 53.090318 -172.812456)
					(xy 53.090318 -173.561248) (xy 53.3781 -173.561248)
				)
			)
		)
	)
)
